# SCM (Grand Teton) — schematic netlist excerpt (pin names and nets, part order shuffled) for the footprints in the layout excerpt that follows; sources: Cadence DE-HDL packaged netlist, KiCad conversion of 12092022_DA0F0TMDCD0_F0T_Management_Board_D_brd_V3_OCP.brd

C172  Q_CAP  470PF 50V 10% X7R  pkg 0402  page 28 : A = P5V_AUX ; B = GND
R881  Q_RES  4.7K 1% EMPTY  pkg 0402LF  page 48 : A = P3V3_AUX ; B = FM_JTAG_TCK_MUX_BMC_SEL_R

(kicad_pcb
	(version 20260206)
	(generator "pcbnew")
	(generator_version "10.0")
	(general
		(thickness 1.6)
		(legacy_teardrops no)
	)
	(paper "A4")
	(title_block
		(title "12092022_DA0F0TMDCD0_F0T_Management_Board_D_brd_V3_OCP.brd")
		(comment 1 "Grand Teton / footprints 434-435 of 1440")
	)
	(layers
		(0 "F.Cu" signal "TOP")
		(4 "In1.Cu" signal "GND")
		(6 "In2.Cu" signal "IN1")
		(8 "In3.Cu" signal "GND1")
		(10 "In4.Cu" signal "IN2")
		(12 "In5.Cu" signal "VCC")
		(14 "In6.Cu" signal "VCC1")
		(16 "In7.Cu" signal "IN3")
		(18 "In8.Cu" signal "GND2")
		(20 "In9.Cu" signal "IN4")
		(22 "In10.Cu" signal "GND3")
		(2 "B.Cu" signal "BOTTOM")
		(9 "F.Adhes" user "F.Adhesive")
		(11 "B.Adhes" user "B.Adhesive")
		(13 "F.Paste" user "Package Geometry/Pastemask Top")
		(15 "B.Paste" user "Package Geometry/Pastemask Bottom")
		(5 "F.SilkS" user "Ref Des/Silkscreen Top")
		(7 "B.SilkS" user "Ref Des/Silkscreen Bottom")
		(1 "F.Mask" user "Board Geometry/Soldermask Top")
		(3 "B.Mask" user "Board Geometry/Soldermask Bottom")
		(17 "Dwgs.User" user "User.Drawings")
		(19 "Cmts.User" user "User.Comments")
		(21 "Eco1.User" user "User.Eco1")
		(23 "Eco2.User" user "User.Eco2")
		(25 "Edge.Cuts" user "Board Geometry/Outline")
		(27 "Margin" user)
		(31 "F.CrtYd" user "Package Geometry/Place Bound Top")
		(29 "B.CrtYd" user "Package Geometry/Place Bound Bottom")
		(35 "F.Fab" user "Ref Des/Assembly Top")
		(33 "B.Fab" user "Ref Des/Assembly Bottom")
	)
	(footprint ""
		(layer "F.Cu")
		(at 54.483 -23.495 90)
		(property "Reference" "C172"
			(at 0 0 90)
			(layer "F.SilkS")
			(hide yes)
			(effects
				(font
					(size 1.27 1.27)
				)
			)
		)
		(property "Value" ""
			(at 0 0 90)
			(layer "F.Fab")
			(effects
				(font
					(size 1.27 1.27)
				)
			)
		)
		(duplicate_pad_numbers_are_jumpers no)
		(fp_line
			(start 0.7874 -0.4064)
			(end 0.7874 0.4064)
			(stroke
				(width 0.1524)
				(type default)
			)
			(layer "F.SilkS")
		)
		(fp_line
			(start -0.7874 -0.4064)
			(end 0.7874 -0.4064)
			(stroke
				(width 0.1524)
				(type default)
			)
			(layer "F.SilkS")
		)
		(fp_line
			(start 0.7874 0.4064)
			(end -0.7874 0.4064)
			(stroke
				(width 0.1524)
				(type default)
			)
			(layer "F.SilkS")
		)
		(fp_line
			(start -0.7874 0.4064)
			(end -0.7874 -0.4064)
			(stroke
				(width 0.1524)
				(type default)
			)
			(layer "F.SilkS")
		)
		(fp_line
			(start -0.12065 -0.305054)
			(end -0.12065 -0.2794)
			(stroke
				(width 0.1)
				(type default)
			)
			(layer "F.Fab")
		)
		(fp_line
			(start -0.67945 -0.305054)
			(end -0.12065 -0.305054)
			(stroke
				(width 0.1)
				(type default)
			)
			(layer "F.Fab")
		)
		(fp_line
			(start 0.67945 -0.3048)
			(end 0.67945 0.3048)
			(stroke
				(width 0.1)
				(type default)
			)
			(layer "F.Fab")
		)
		(fp_line
			(start 0.12065 -0.3048)
			(end 0.67945 -0.3048)
			(stroke
				(width 0.1)
				(type default)
			)
			(layer "F.Fab")
		)
		(fp_line
			(start 0.12065 -0.2794)
			(end 0.12065 -0.3048)
			(stroke
				(width 0.1)
				(type default)
			)
			(layer "F.Fab")
		)
		(fp_line
			(start -0.12065 -0.2794)
			(end 0.12065 -0.2794)
			(stroke
				(width 0.1)
				(type default)
			)
			(layer "F.Fab")
		)
		(fp_line
			(start 0.120396 0.2794)
			(end -0.12065 0.2794)
			(stroke
				(width 0.1)
				(type default)
			)
			(layer "F.Fab")
		)
		(fp_line
			(start -0.12065 0.2794)
			(end -0.12065 0.3048)
			(stroke
				(width 0.1)
				(type default)
			)
			(layer "F.Fab")
		)
		(fp_line
			(start 0.67945 0.3048)
			(end 0.120396 0.3048)
			(stroke
				(width 0.1)
				(type default)
			)
			(layer "F.Fab")
		)
		(fp_line
			(start 0.120396 0.3048)
			(end 0.120396 0.2794)
			(stroke
				(width 0.1)
				(type default)
			)
			(layer "F.Fab")
		)
		(fp_line
			(start -0.12065 0.3048)
			(end -0.67945 0.3048)
			(stroke
				(width 0.1)
				(type default)
			)
			(layer "F.Fab")
		)
		(fp_line
			(start -0.67945 0.3048)
			(end -0.67945 -0.305054)
			(stroke
				(width 0.1)
				(type default)
			)
			(layer "F.Fab")
		)
		(pad "1" smd circle
			(at -0.40005 0 90)
			(size 0 0)
			(layers "F.Cu" "F.Mask" "F.Paste")
			(net "P5V_AUX")
		)
		(pad "2" smd circle
			(at 0.40005 0 90)
			(size 0 0)
			(layers "F.Cu" "F.Mask" "F.Paste")
			(net "GND")
		)
	)
	(footprint ""
		(layer "F.Cu")
		(at 75.946 -74.422 -90)
		(property "Reference" "R881"
			(at 0 0 270)
			(layer "F.SilkS")
			(hide yes)
			(effects
				(font
					(size 1.27 1.27)
				)
			)
		)
		(property "Value" ""
			(at 0 0 270)
			(layer "F.Fab")
			(effects
				(font
					(size 1.27 1.27)
				)
			)
		)
		(duplicate_pad_numbers_are_jumpers no)
		(fp_line
			(start -0.7874 0.4064)
			(end -0.7874 -0.4064)
			(stroke
				(width 0.1524)
				(type default)
			)
			(layer "F.SilkS")
		)
		(fp_line
			(start 0.7874 0.4064)
			(end -0.7874 0.4064)
			(stroke
				(width 0.1524)
				(type default)
			)
			(layer "F.SilkS")
		)
		(fp_line
			(start -0.7874 -0.4064)
			(end 0.7874 -0.4064)
			(stroke
				(width 0.1524)
				(type default)
			)
			(layer "F.SilkS")
		)
		(fp_line
			(start 0.7874 -0.4064)
			(end 0.7874 0.4064)
			(stroke
				(width 0.1524)
				(type default)
			)
			(layer "F.SilkS")
		)
		(fp_line
			(start -0.67945 0.3048)
			(end -0.67945 -0.305054)
			(stroke
				(width 0.1)
				(type default)
			)
			(layer "F.Fab")
		)
		(fp_line
			(start -0.12065 0.3048)
			(end -0.67945 0.3048)
			(stroke
				(width 0.1)
				(type default)
			)
			(layer "F.Fab")
		)
		(fp_line
			(start 0.120396 0.3048)
			(end 0.120396 0.2794)
			(stroke
				(width 0.1)
				(type default)
			)
			(layer "F.Fab")
		)
		(fp_line
			(start 0.67945 0.3048)
			(end 0.120396 0.3048)
			(stroke
				(width 0.1)
				(type default)
			)
			(layer "F.Fab")
		)
		(fp_line
			(start -0.12065 0.2794)
			(end -0.12065 0.3048)
			(stroke
				(width 0.1)
				(type default)
			)
			(layer "F.Fab")
		)
		(fp_line
			(start 0.120396 0.2794)
			(end -0.12065 0.2794)
			(stroke
				(width 0.1)
				(type default)
			)
			(layer "F.Fab")
		)
		(fp_line
			(start -0.12065 -0.2794)
			(end 0.12065 -0.2794)
			(stroke
				(width 0.1)
				(type default)
			)
			(layer "F.Fab")
		)
		(fp_line
			(start 0.12065 -0.2794)
			(end 0.12065 -0.3048)
			(stroke
				(width 0.1)
				(type default)
			)
			(layer "F.Fab")
		)
		(fp_line
			(start 0.12065 -0.3048)
			(end 0.67945 -0.3048)
			(stroke
				(width 0.1)
				(type default)
			)
			(layer "F.Fab")
		)
		(fp_line
			(start 0.67945 -0.3048)
			(end 0.67945 0.3048)
			(stroke
				(width 0.1)
				(type default)
			)
			(layer "F.Fab")
		)
		(fp_line
			(start -0.67945 -0.305054)
			(end -0.12065 -0.305054)
			(stroke
				(width 0.1)
				(type default)
			)
			(layer "F.Fab")
		)
		(fp_line
			(start -0.12065 -0.305054)
			(end -0.12065 -0.2794)
			(stroke
				(width 0.1)
				(type default)
			)
			(layer "F.Fab")
		)
		(pad "1" smd circle
			(at -0.40005 0 270)
			(size 0 0)
			(layers "F.Cu" "F.Mask" "F.Paste")
			(net "P3V3_AUX")
		)
		(pad "2" smd circle
			(at 0.40005 0 270)
			(size 0 0)
			(layers "F.Cu" "F.Mask" "F.Paste")
			(net "FM_JTAG_TCK_MUX_BMC_SEL_R")
		)
	)
)
